# SCM (Grand Teton) — schematic netlist excerpt (pin names and nets, part order shuffled) for the footprints in the layout excerpt that follows; sources: Cadence DE-HDL packaged netlist, KiCad conversion of 12092022_DA0F0TMDCD0_F0T_Management_Board_D_brd_V3_OCP.brd

C120  Q_CAP  22UF 6.3V 20% X6S  pkg C0603  page 16 : A = P3V3_AUX ; B = GND
C60  Q_CAP  1UF 25V 10% X6S  pkg C0402  page 17 : A = P3V3_STBY_PLLAHVDD ; B = GND

(kicad_pcb
	(version 20260206)
	(generator "pcbnew")
	(generator_version "10.0")
	(general
		(thickness 1.6)
		(legacy_teardrops no)
	)
	(paper "A4")
	(title_block
		(title "12092022_DA0F0TMDCD0_F0T_Management_Board_D_brd_V3_OCP.brd")
		(comment 1 "Grand Teton / footprints 962-963 of 1440")
	)
	(layers
		(0 "F.Cu" signal "TOP")
		(4 "In1.Cu" signal "GND")
		(6 "In2.Cu" signal "IN1")
		(8 "In3.Cu" signal "GND1")
		(10 "In4.Cu" signal "IN2")
		(12 "In5.Cu" signal "VCC")
		(14 "In6.Cu" signal "VCC1")
		(16 "In7.Cu" signal "IN3")
		(18 "In8.Cu" signal "GND2")
		(20 "In9.Cu" signal "IN4")
		(22 "In10.Cu" signal "GND3")
		(2 "B.Cu" signal "BOTTOM")
		(9 "F.Adhes" user "F.Adhesive")
		(11 "B.Adhes" user "B.Adhesive")
		(13 "F.Paste" user "Package Geometry/Pastemask Top")
		(15 "B.Paste" user "Package Geometry/Pastemask Bottom")
		(5 "F.SilkS" user "Ref Des/Silkscreen Top")
		(7 "B.SilkS" user "Ref Des/Silkscreen Bottom")
		(1 "F.Mask" user "Board Geometry/Soldermask Top")
		(3 "B.Mask" user "Board Geometry/Soldermask Bottom")
		(17 "Dwgs.User" user "User.Drawings")
		(19 "Cmts.User" user "User.Comments")
		(21 "Eco1.User" user "User.Eco1")
		(23 "Eco2.User" user "User.Eco2")
		(25 "Edge.Cuts" user "Board Geometry/Outline")
		(27 "Margin" user)
		(31 "F.CrtYd" user "Package Geometry/Place Bound Top")
		(29 "B.CrtYd" user "Package Geometry/Place Bound Bottom")
		(35 "F.Fab" user "Ref Des/Assembly Top")
		(33 "B.Fab" user "Ref Des/Assembly Bottom")
	)
	(footprint ""
		(layer "B.Cu")
		(at 53.532024 -45.280326)
		(property "Reference" "C60"
			(at 0 0 0)
			(layer "B.SilkS")
			(hide yes)
			(effects
				(font
					(size 1.27 1.27)
				)
				(justify mirror)
			)
		)
		(property "Value" ""
			(at 0 0 0)
			(layer "B.Fab")
			(effects
				(font
					(size 1.27 1.27)
				)
				(justify mirror)
			)
		)
		(duplicate_pad_numbers_are_jumpers no)
		(fp_line
			(start -0.7874 -0.4064)
			(end -0.7874 0.4064)
			(stroke
				(width 0.1524)
				(type default)
			)
			(layer "B.SilkS")
		)
		(fp_line
			(start -0.7874 0.4064)
			(end 0.7874 0.4064)
			(stroke
				(width 0.1524)
				(type default)
			)
			(layer "B.SilkS")
		)
		(fp_line
			(start 0.7874 -0.4064)
			(end -0.7874 -0.4064)
			(stroke
				(width 0.1524)
				(type default)
			)
			(layer "B.SilkS")
		)
		(fp_line
			(start 0.7874 0.4064)
			(end 0.7874 -0.4064)
			(stroke
				(width 0.1524)
				(type default)
			)
			(layer "B.SilkS")
		)
		(fp_line
			(start -0.67945 -0.3048)
			(end -0.67945 0.3048)
			(stroke
				(width 0.1)
				(type default)
			)
			(layer "B.Fab")
		)
		(fp_line
			(start -0.67945 0.3048)
			(end -0.120396 0.3048)
			(stroke
				(width 0.1)
				(type default)
			)
			(layer "B.Fab")
		)
		(fp_line
			(start -0.12065 -0.3048)
			(end -0.67945 -0.3048)
			(stroke
				(width 0.1)
				(type default)
			)
			(layer "B.Fab")
		)
		(fp_line
			(start -0.12065 -0.2794)
			(end -0.12065 -0.3048)
			(stroke
				(width 0.1)
				(type default)
			)
			(layer "B.Fab")
		)
		(fp_line
			(start -0.120396 0.2794)
			(end 0.12065 0.2794)
			(stroke
				(width 0.1)
				(type default)
			)
			(layer "B.Fab")
		)
		(fp_line
			(start -0.120396 0.3048)
			(end -0.120396 0.2794)
			(stroke
				(width 0.1)
				(type default)
			)
			(layer "B.Fab")
		)
		(fp_line
			(start 0.12065 -0.305054)
			(end 0.12065 -0.2794)
			(stroke
				(width 0.1)
				(type default)
			)
			(layer "B.Fab")
		)
		(fp_line
			(start 0.12065 -0.2794)
			(end -0.12065 -0.2794)
			(stroke
				(width 0.1)
				(type default)
			)
			(layer "B.Fab")
		)
		(fp_line
			(start 0.12065 0.2794)
			(end 0.12065 0.3048)
			(stroke
				(width 0.1)
				(type default)
			)
			(layer "B.Fab")
		)
		(fp_line
			(start 0.12065 0.3048)
			(end 0.67945 0.3048)
			(stroke
				(width 0.1)
				(type default)
			)
			(layer "B.Fab")
		)
		(fp_line
			(start 0.67945 -0.305054)
			(end 0.12065 -0.305054)
			(stroke
				(width 0.1)
				(type default)
			)
			(layer "B.Fab")
		)
		(fp_line
			(start 0.67945 0.3048)
			(end 0.67945 -0.305054)
			(stroke
				(width 0.1)
				(type default)
			)
			(layer "B.Fab")
		)
		(pad "1" smd circle
			(at 0.40005 0 180)
			(size 0 0)
			(layers "B.Cu" "B.Mask" "B.Paste")
			(net "P3V3_STBY_PLLAHVDD")
		)
		(pad "2" smd circle
			(at -0.40005 0 180)
			(size 0 0)
			(layers "B.Cu" "B.Mask" "B.Paste")
			(net "GND")
		)
	)
	(footprint ""
		(layer "B.Cu")
		(at 82.804 -32.766 -90)
		(property "Reference" "C120"
			(at 0 0 90)
			(layer "B.SilkS")
			(hide yes)
			(effects
				(font
					(size 1.27 1.27)
				)
				(justify mirror)
			)
		)
		(property "Value" ""
			(at 0 0 90)
			(layer "B.Fab")
			(effects
				(font
					(size 1.27 1.27)
				)
				(justify mirror)
			)
		)
		(duplicate_pad_numbers_are_jumpers no)
		(fp_line
			(start -1.2954 0.5842)
			(end 1.2954 0.5842)
			(stroke
				(width 0.1524)
				(type default)
			)
			(layer "B.SilkS")
		)
		(fp_line
			(start 1.2954 0.5842)
			(end 1.2954 -0.5842)
			(stroke
				(width 0.1524)
				(type default)
			)
			(layer "B.SilkS")
		)
		(fp_line
			(start -1.2954 -0.5842)
			(end -1.2954 0.5842)
			(stroke
				(width 0.1524)
				(type default)
			)
			(layer "B.SilkS")
		)
		(fp_line
			(start 0 -0.5842)
			(end 0 0.5842)
			(stroke
				(width 0.1524)
				(type default)
			)
			(layer "B.SilkS")
		)
		(fp_line
			(start 1.2954 -0.5842)
			(end -1.2954 -0.5842)
			(stroke
				(width 0.1524)
				(type default)
			)
			(layer "B.SilkS")
		)
		(fp_line
			(start -0.8636 0.4572)
			(end 0.8636 0.4572)
			(stroke
				(width 0.1)
				(type default)
			)
			(layer "B.Fab")
		)
		(fp_line
			(start 0.8636 0.4572)
			(end 0.8636 0.4064)
			(stroke
				(width 0.1)
				(type default)
			)
			(layer "B.Fab")
		)
		(fp_line
			(start -1.1938 0.4064)
			(end -0.8636 0.4064)
			(stroke
				(width 0.1)
				(type default)
			)
			(layer "B.Fab")
		)
		(fp_line
			(start -0.8636 0.4064)
			(end -0.8636 0.4572)
			(stroke
				(width 0.1)
				(type default)
			)
			(layer "B.Fab")
		)
		(fp_line
			(start 0.8636 0.4064)
			(end 1.1938 0.4064)
			(stroke
				(width 0.1)
				(type default)
			)
			(layer "B.Fab")
		)
		(fp_line
			(start 1.1938 0.4064)
			(end 1.1938 -0.4064)
			(stroke
				(width 0.1)
				(type default)
			)
			(layer "B.Fab")
		)
		(fp_line
			(start -1.1938 -0.4064)
			(end -1.1938 0.4064)
			(stroke
				(width 0.1)
				(type default)
			)
			(layer "B.Fab")
		)
		(fp_line
			(start -0.8636 -0.4064)
			(end -1.1938 -0.4064)
			(stroke
				(width 0.1)
				(type default)
			)
			(layer "B.Fab")
		)
		(fp_line
			(start 0.8636 -0.4064)
			(end 0.8636 -0.4572)
			(stroke
				(width 0.1)
				(type default)
			)
			(layer "B.Fab")
		)
		(fp_line
			(start 1.1938 -0.4064)
			(end 0.8636 -0.4064)
			(stroke
				(width 0.1)
				(type default)
			)
			(layer "B.Fab")
		)
		(fp_line
			(start -0.8636 -0.4572)
			(end -0.8636 -0.4064)
			(stroke
				(width 0.1)
				(type default)
			)
			(layer "B.Fab")
		)
		(fp_line
			(start 0.8636 -0.4572)
			(end -0.8636 -0.4572)
			(stroke
				(width 0.1)
				(type default)
			)
			(layer "B.Fab")
		)
		(pad "1" smd rect
			(at 0.7366 0 180)
			(size 0.7112 0.8128)
			(layers "B.Cu" "B.Mask" "B.Paste")
			(net "P3V3_AUX")
		)
		(pad "2" smd rect
			(at -0.7366 0 180)
			(size 0.7112 0.8128)
			(layers "B.Cu" "B.Mask" "B.Paste")
			(net "GND")
		)
	)
)
